# BASEBOARD_FAB2 (Tioga Pass) — schematic netlist excerpt (pin names and nets, part order shuffled) for the footprints in the layout excerpt that follows; sources: Cadence DE-HDL packaged netlist, KiCad conversion of Wiwynn_Tioga_Pass_MB.brd

CT6  CAP_A  0.1UF 16V 10% X7R  pkg 0402V  page 202 : A = VR_PVCCIN_CPU0_AIREF2 ; B = GND

Q12W2  BSL308C-H6327-GP  pkg DISCRET-GB1  page 197
  \gate#1\  = PWRGD_PVDDQ_DEF
  \source#2\  = P12V_NVDIMM_DEF
  \gate#3\  = PWRGD_PVDDQ_DEF_N
  \drain#4\  = P12V_NVDIMM_DEF_D
  \source#5\  = GND
  \drain#6\  = PWRGD_PVDDQ_DEF_N

(kicad_pcb
	(version 20260206)
	(generator "pcbnew")
	(generator_version "10.0")
	(general
		(thickness 1.6)
		(legacy_teardrops no)
	)
	(paper "A4")
	(title_block
		(title "Wiwynn_Tioga_Pass_MB.brd")
		(comment 1 "Tioga Pass / footprints 326-327 of 4770")
	)
	(layers
		(0 "F.Cu" signal "TOP")
		(4 "In1.Cu" signal "L2GND")
		(6 "In2.Cu" signal "L3")
		(8 "In3.Cu" signal "L4GND")
		(10 "In4.Cu" signal "L5")
		(12 "In5.Cu" signal "L6GND")
		(14 "In6.Cu" signal "L7VCC")
		(16 "In7.Cu" signal "L8VCC")
		(18 "In8.Cu" signal "L9GND")
		(20 "In9.Cu" signal "L10")
		(22 "In10.Cu" signal "L11GND")
		(24 "In11.Cu" signal "L12")
		(26 "In12.Cu" signal "L13GND")
		(2 "B.Cu" signal "BOTTOM")
		(9 "F.Adhes" user "F.Adhesive")
		(11 "B.Adhes" user "B.Adhesive")
		(13 "F.Paste" user "Package Geometry/Pastemask Top")
		(15 "B.Paste" user "Package Geometry/Pastemask Bottom")
		(5 "F.SilkS" user "Ref Des/Silkscreen Top")
		(7 "B.SilkS" user "Ref Des/Silkscreen Bottom")
		(1 "F.Mask" user "Board Geometry/Soldermask Top")
		(3 "B.Mask" user "Board Geometry/Soldermask Bottom")
		(17 "Dwgs.User" user "User.Drawings")
		(19 "Cmts.User" user "User.Comments")
		(21 "Eco1.User" user "User.Eco1")
		(23 "Eco2.User" user "User.Eco2")
		(25 "Edge.Cuts" user "Board Geometry/Outline")
		(27 "Margin" user)
		(31 "F.CrtYd" user "Package Geometry/Place Bound Top")
		(29 "B.CrtYd" user "Package Geometry/Place Bound Bottom")
		(35 "F.Fab" user "Ref Des/Assembly Top")
		(33 "B.Fab" user "Ref Des/Assembly Bottom")
	)
	(footprint ""
		(layer "F.Cu")
		(at 185.886598 -126.97333 90)
		(property "Reference" "Q12W2"
			(at 0 0 90)
			(layer "F.SilkS")
			(hide yes)
			(effects
				(font
					(size 1.27 1.27)
				)
			)
		)
		(property "Value" "*"
			(at -4.572 -7.6835 90)
			(unlocked yes)
			(layer "F.Fab")
			(hide yes)
			(effects
				(font
					(size 1.27 1.016)
					(thickness 0.1524)
				)
			)
		)
		(property "Device Type" "BSL308C-H6327-GP_DISCRET-GB1-BA"
			(at -4.572 -9.2075 90)
			(unlocked yes)
			(layer "F.Fab")
			(hide yes)
			(effects
				(font
					(size 1.27 1.016)
					(thickness 0.1524)
				)
			)
		)
		(duplicate_pad_numbers_are_jumpers no)
		(fp_line
			(start 1.102868 -0.081534)
			(end 1.102868 0.081534)
			(stroke
				(width 0.1524)
				(type default)
			)
			(layer "F.SilkS")
		)
		(fp_line
			(start -1.8796 -0.081534)
			(end 1.102868 -0.081534)
			(stroke
				(width 0.1524)
				(type default)
			)
			(layer "F.SilkS")
		)
		(fp_line
			(start -1.8796 -0.081534)
			(end -1.524 0)
			(stroke
				(width 0.1524)
				(type default)
			)
			(layer "F.SilkS")
		)
		(fp_line
			(start -1.524 0)
			(end -1.8796 0.081534)
			(stroke
				(width 0.1524)
				(type default)
			)
			(layer "F.SilkS")
		)
		(fp_line
			(start 1.102868 0.081534)
			(end -1.8796 0.081534)
			(stroke
				(width 0.1524)
				(type default)
			)
			(layer "F.SilkS")
		)
		(fp_line
			(start -1.8796 0.081534)
			(end -1.8796 -0.081534)
			(stroke
				(width 0.1524)
				(type default)
			)
			(layer "F.SilkS")
		)
		(fp_line
			(start -1.7018 0.3048)
			(end -1.7018 1.8796)
			(stroke
				(width 0.508)
				(type default)
			)
			(layer "F.SilkS")
		)
		(fp_poly
			(pts
				(xy -1.179068 0.081534) (xy -1.179068 -0.081534) (xy 1.102868 -0.081534) (xy 1.102868 0.081534)
			)
			(stroke
				(width 0)
				(type default)
			)
			(fill yes)
			(layer "F.SilkS")
		)
		(fp_poly
			(pts
				(xy -1.4478 1.2446) (xy 1.4478 1.2446) (xy 1.4478 -1.2446) (xy -1.4478 -1.2446)
			)
			(stroke
				(width 0)
				(type default)
			)
			(fill no)
			(layer "F.CrtYd")
		)
		(fp_poly
			(pts
				(xy -1.4478 -1.23952) (xy -1.9558 -1.23952) (xy -1.9558 2.1336) (xy 1.9558 2.1336) (xy 1.9558 -2.1336)
				(xy -1.9558 -2.1336) (xy -1.9558 -1.2446) (xy 1.4478 -1.2446) (xy 1.4478 1.2446) (xy -1.4478 1.2446)
			)
			(stroke
				(width 0)
				(type default)
			)
			(fill no)
			(layer "F.CrtYd")
		)
		(fp_rect
			(start -1.9558 2.1336)
			(end 1.9558 -2.1336)
			(stroke
				(width 0)
				(type default)
			)
			(fill no)
			(layer "F.Fab")
		)
		(pad "1" smd rect
			(at -0.950468 0.995934 90)
			(size 0.4572 1.27)
			(layers "F.Cu" "F.Mask" "F.Paste")
			(net "PWRGD_PVDDQ_DEF")
		)
		(pad "2" smd rect
			(at 0 0.995934 90)
			(size 0.4572 1.27)
			(layers "F.Cu" "F.Mask" "F.Paste")
			(net "P12V_NVDIMM_DEF")
		)
		(pad "3" smd rect
			(at 0.950468 0.995934 90)
			(size 0.4572 1.27)
			(layers "F.Cu" "F.Mask" "F.Paste")
			(net "PWRGD_PVDDQ_DEF_N")
		)
		(pad "4" smd rect
			(at 0.950468 -0.995934 90)
			(size 0.4572 1.27)
			(layers "F.Cu" "F.Mask" "F.Paste")
			(net "P12V_NVDIMM_DEF_D")
		)
		(pad "5" smd rect
			(at 0 -0.995934 90)
			(size 0.4572 1.27)
			(layers "F.Cu" "F.Mask" "F.Paste")
			(net "GND")
		)
		(pad "6" smd rect
			(at -0.950468 -0.995934 90)
			(size 0.4572 1.27)
			(layers "F.Cu" "F.Mask" "F.Paste")
			(net "PWRGD_PVDDQ_DEF_N")
		)
	)
	(footprint ""
		(layer "F.Cu")
		(at 194.142614 -61.732668)
		(property "Reference" "CT6"
			(at -0.48387 -4.9022 270)
			(unlocked yes)
			(layer "F.SilkS")
			(effects
				(font
					(size 0.7874 0.5842)
					(thickness 0.1524)
				)
				(justify left)
			)
		)
		(property "Value" ""
			(at 0 0 0)
			(layer "F.Fab")
			(effects
				(font
					(size 1.27 1.27)
				)
			)
		)
		(duplicate_pad_numbers_are_jumpers no)
		(fp_poly
			(pts
				(xy 0.3048 -0.1016) (xy 0.3048 0.9906) (xy -0.3048 0.9906) (xy -0.3048 -0.1016)
			)
			(stroke
				(width 0)
				(type default)
			)
			(fill no)
			(layer "F.CrtYd")
		)
		(fp_line
			(start -0.3048 -0.1016)
			(end -0.3048 0.9906)
			(stroke
				(width 0.1)
				(type default)
			)
			(layer "F.Fab")
		)
		(fp_line
			(start -0.3048 0.9906)
			(end 0.3048 0.9906)
			(stroke
				(width 0.1)
				(type default)
			)
			(layer "F.Fab")
		)
		(fp_line
			(start 0.3048 -0.1016)
			(end -0.3048 -0.1016)
			(stroke
				(width 0.1)
				(type default)
			)
			(layer "F.Fab")
		)
		(fp_line
			(start 0.3048 0.9906)
			(end 0.3048 -0.1016)
			(stroke
				(width 0.1)
				(type default)
			)
			(layer "F.Fab")
		)
		(pad "1" smd rect
			(at 0 0)
			(size 0.508 0.508)
			(layers "F.Cu" "F.Mask" "F.Paste")
			(net "VR_PVCCIN_CPU0_AIREF2")
		)
		(pad "2" smd rect
			(at 0 0.889)
			(size 0.508 0.508)
			(layers "F.Cu" "F.Mask" "F.Paste")
			(net "GND")
		)
		(zone
			(layer "F.Cu")
			(hatch none 0.5)
			(connect_pads
				(clearance 0)
			)
			(min_thickness 0.25)
			(keepout
				(tracks allowed)
				(vias not_allowed)
				(pads allowed)
				(copperpour not_allowed)
				(footprints allowed)
			)
			(placement
				(enabled no)
				(sheetname "")
			)
			(fill
				(thermal_gap 0.5)
				(thermal_bridge_width 0.5)
				(island_removal_mode 0)
			)
			(polygon
				(pts
					(xy 193.888614 -61.478668) (xy 194.396614 -61.478668) (xy 194.396614 -61.097668) (xy 193.888614 -61.097668)
				)
			)
		)
		(zone
			(layer "F.Cu")
			(hatch none 0.5)
			(connect_pads
				(clearance 0)
			)
			(min_thickness 0.25)
			(keepout
				(tracks not_allowed)
				(vias allowed)
				(pads allowed)
				(copperpour not_allowed)
				(footprints allowed)
			)
			(placement
				(enabled no)
				(sheetname "")
			)
			(fill
				(thermal_gap 0.5)
				(thermal_bridge_width 0.5)
				(island_removal_mode 0)
			)
			(polygon
				(pts
					(xy 193.888614 -61.097668) (xy 194.396614 -61.097668) (xy 194.396614 -61.478668) (xy 193.888614 -61.478668)
				)
			)
		)
	)
)
